(kicad_pcb
	(version 20260206)
	(generator "pcbnew")
	(generator_version "10.0")
	(general
		(thickness 1.6)
		(legacy_teardrops no)
	)
	(paper "A4")
	(title_block
		(title "peb — Lightning_PEB_BRD.brd")
		(comment 1 "Lightning (Wiwynn / Facebook NVMe JBOF) / footprints 1196-1203 of 2563")
	)
	(layers
		(0 "F.Cu" signal "TOP")
		(4 "In1.Cu" signal "L2GND")
		(6 "In2.Cu" signal "L3")
		(8 "In3.Cu" signal "L4VCC")
		(10 "In4.Cu" signal "L5VCC")
		(12 "In5.Cu" signal "L6")
		(14 "In6.Cu" signal "L7GND")
		(2 "B.Cu" signal "BOTTOM")
		(9 "F.Adhes" user "F.Adhesive")
		(11 "B.Adhes" user "B.Adhesive")
		(13 "F.Paste" user "Package Geometry/Pastemask Top")
		(15 "B.Paste" user "Package Geometry/Pastemask Bottom")
		(5 "F.SilkS" user "Ref Des/Silkscreen Top")
		(7 "B.SilkS" user "Ref Des/Silkscreen Bottom")
		(1 "F.Mask" user "Board Geometry/Soldermask Top")
		(3 "B.Mask" user "Board Geometry/Soldermask Bottom")
		(17 "Dwgs.User" user "User.Drawings")
		(19 "Cmts.User" user "User.Comments")
		(21 "Eco1.User" user "User.Eco1")
		(23 "Eco2.User" user "User.Eco2")
		(25 "Edge.Cuts" user "Board Geometry/Outline")
		(27 "Margin" user)
		(31 "F.CrtYd" user "Package Geometry/Place Bound Top")
		(29 "B.CrtYd" user "Package Geometry/Place Bound Bottom")
		(35 "F.Fab" user "Ref Des/Assembly Top")
		(33 "B.Fab" user "Ref Des/Assembly Bottom")
	)
	(footprint ""
		(layer "F.Cu")
		(at 34.08172 -79.048356 90)
		(property "Reference" "PR1"
			(at 0 0 90)
			(layer "F.SilkS")
			(hide yes)
			(effects
				(font
					(size 1.27 1.27)
				)
			)
		)
		(property "Value" "13K3R2F-L1-GP"
			(at 0.064008 -3.993896 90)
			(unlocked yes)
			(layer "F.Fab")
			(hide yes)
			(effects
				(font
					(size 1.016 1.016)
					(thickness 0.1524)
				)
			)
		)
		(property "Device Type" "R402H16"
			(at 0.064008 -5.517896 90)
			(unlocked yes)
			(layer "F.Fab")
			(hide yes)
			(effects
				(font
					(size 1.016 1.016)
					(thickness 0.1524)
				)
			)
		)
		(duplicate_pad_numbers_are_jumpers no)
		(fp_line
			(start 0.508 -0.9398)
			(end -0.508 -0.9398)
			(stroke
				(width 0.1524)
				(type default)
			)
			(layer "F.SilkS")
		)
		(fp_line
			(start -0.508 -0.9398)
			(end -0.508 0.9398)
			(stroke
				(width 0.1524)
				(type default)
			)
			(layer "F.SilkS")
		)
		(fp_rect
			(start -0.508 0.9398)
			(end 0.508 -0.9398)
			(stroke
				(width 0)
				(type default)
			)
			(fill no)
			(layer "F.CrtYd")
		)
		(fp_rect
			(start -0.508 0.9398)
			(end 0.508 -0.9398)
			(stroke
				(width 0)
				(type default)
			)
			(fill no)
			(layer "F.Fab")
		)
		(pad "1" smd custom
			(at 0 -0.4445 90)
			(size 0.1397 0.1397)
			(layers "F.Cu" "F.Mask" "F.Paste")
			(net "P5V_STBY_FB")
			(options
				(clearance outline)
				(anchor circle)
			)
			(primitives
				(gr_poly
					(pts
						(arc
							(start -0.1778 -0.2794)
							(mid -0.249642 -0.249642)
							(end -0.2794 -0.1778)
						)
						(arc
							(start -0.2794 0.1778)
							(mid -0.249642 0.249642)
							(end -0.1778 0.2794)
						)
						(arc
							(start 0.1778 0.2794)
							(mid 0.249642 0.249642)
							(end 0.2794 0.1778)
						)
						(arc
							(start 0.2794 -0.1778)
							(mid 0.249642 -0.249642)
							(end 0.1778 -0.2794)
						)
					)
					(width 0)
					(fill yes)
				)
			)
		)
		(pad "2" smd custom
			(at 0 0.4445 90)
			(size 0.1397 0.1397)
			(layers "F.Cu" "F.Mask" "F.Paste")
			(net "GND")
			(options
				(clearance outline)
				(anchor circle)
			)
			(primitives
				(gr_poly
					(pts
						(arc
							(start -0.1778 -0.2794)
							(mid -0.249642 -0.249642)
							(end -0.2794 -0.1778)
						)
						(arc
							(start -0.2794 0.1778)
							(mid -0.249642 0.249642)
							(end -0.1778 0.2794)
						)
						(arc
							(start 0.1778 0.2794)
							(mid 0.249642 0.249642)
							(end 0.2794 0.1778)
						)
						(arc
							(start 0.2794 -0.1778)
							(mid 0.249642 -0.249642)
							(end 0.1778 -0.2794)
						)
					)
					(width 0)
					(fill yes)
				)
			)
		)
	)
	(footprint ""
		(layer "F.Cu")
		(at 68.8594 -123.3932 -90)
		(property "Reference" "R309"
			(at 0 0 270)
			(layer "F.SilkS")
			(hide yes)
			(effects
				(font
					(size 1.27 1.27)
				)
			)
		)
		(property "Value" "4K7R2F-GP"
			(at 0.064008 -3.993896 270)
			(unlocked yes)
			(layer "F.Fab")
			(hide yes)
			(effects
				(font
					(size 1.016 1.016)
					(thickness 0.1524)
				)
			)
		)
		(property "Device Type" "R402H16"
			(at 0.064008 -5.517896 270)
			(unlocked yes)
			(layer "F.Fab")
			(hide yes)
			(effects
				(font
					(size 1.016 1.016)
					(thickness 0.1524)
				)
			)
		)
		(duplicate_pad_numbers_are_jumpers no)
		(fp_line
			(start -0.508 -0.9398)
			(end -0.508 0.9398)
			(stroke
				(width 0.1524)
				(type default)
			)
			(layer "F.SilkS")
		)
		(fp_line
			(start 0.508 -0.9398)
			(end -0.508 -0.9398)
			(stroke
				(width 0.1524)
				(type default)
			)
			(layer "F.SilkS")
		)
		(fp_rect
			(start -0.508 0.9398)
			(end 0.508 -0.9398)
			(stroke
				(width 0)
				(type default)
			)
			(fill no)
			(layer "F.CrtYd")
		)
		(fp_rect
			(start -0.508 0.9398)
			(end 0.508 -0.9398)
			(stroke
				(width 0)
				(type default)
			)
			(fill no)
			(layer "F.Fab")
		)
		(pad "1" smd custom
			(at 0 -0.4445 270)
			(size 0.1397 0.1397)
			(layers "F.Cu" "F.Mask" "F.Paste")
			(net "P3V3_STBY")
			(options
				(clearance outline)
				(anchor circle)
			)
			(primitives
				(gr_poly
					(pts
						(arc
							(start -0.1778 -0.2794)
							(mid -0.249642 -0.249642)
							(end -0.2794 -0.1778)
						)
						(arc
							(start -0.2794 0.1778)
							(mid -0.249642 0.249642)
							(end -0.1778 0.2794)
						)
						(arc
							(start 0.1778 0.2794)
							(mid 0.249642 0.249642)
							(end 0.2794 0.1778)
						)
						(arc
							(start 0.2794 -0.1778)
							(mid 0.249642 -0.249642)
							(end 0.1778 -0.2794)
						)
					)
					(width 0)
					(fill yes)
				)
			)
		)
		(pad "2" smd custom
			(at 0 0.4445 270)
			(size 0.1397 0.1397)
			(layers "F.Cu" "F.Mask" "F.Paste")
			(net "I2C4_LS_G1")
			(options
				(clearance outline)
				(anchor circle)
			)
			(primitives
				(gr_poly
					(pts
						(arc
							(start -0.1778 -0.2794)
							(mid -0.249642 -0.249642)
							(end -0.2794 -0.1778)
						)
						(arc
							(start -0.2794 0.1778)
							(mid -0.249642 0.249642)
							(end -0.1778 0.2794)
						)
						(arc
							(start 0.1778 0.2794)
							(mid 0.249642 0.249642)
							(end 0.2794 0.1778)
						)
						(arc
							(start 0.2794 -0.1778)
							(mid 0.249642 -0.249642)
							(end 0.1778 -0.2794)
						)
					)
					(width 0)
					(fill yes)
				)
			)
		)
	)
	(footprint ""
		(layer "F.Cu")
		(at 125.832362 -39.469568 180)
		(property "Reference" "Q26"
			(at 0 0 180)
			(layer "F.SilkS")
			(hide yes)
			(effects
				(font
					(size 1.27 1.27)
				)
			)
		)
		(property "Value" "2N7002K-1-GP"
			(at 0.127 -8.9662 180)
			(unlocked yes)
			(layer "F.Fab")
			(hide yes)
			(effects
				(font
					(size 1.016 1.016)
					(thickness 0.1524)
				)
			)
		)
		(property "Device Type" "SOT23DGS2D4H44"
			(at 0.127 -10.4902 180)
			(unlocked yes)
			(layer "F.Fab")
			(hide yes)
			(effects
				(font
					(size 1.016 1.016)
					(thickness 0.1524)
				)
			)
		)
		(duplicate_pad_numbers_are_jumpers no)
		(fp_line
			(start 1.651 1.778)
			(end 1.651 -1.778)
			(stroke
				(width 0.1524)
				(type default)
			)
			(layer "F.SilkS")
		)
		(fp_line
			(start 1.651 -1.778)
			(end -1.651 -1.778)
			(stroke
				(width 0.1524)
				(type default)
			)
			(layer "F.SilkS")
		)
		(fp_line
			(start -1.651 1.778)
			(end 1.651 1.778)
			(stroke
				(width 0.1524)
				(type default)
			)
			(layer "F.SilkS")
		)
		(fp_line
			(start -1.651 -1.778)
			(end -1.651 1.778)
			(stroke
				(width 0.1524)
				(type default)
			)
			(layer "F.SilkS")
		)
		(fp_poly
			(pts
				(xy -1.778 1.8796) (xy -1.778 -1.8796) (xy 1.778 -1.8796) (xy 1.778 1.8796)
			)
			(stroke
				(width 0)
				(type default)
			)
			(fill no)
			(layer "F.CrtYd")
		)
		(fp_poly
			(pts
				(xy -1.778 1.8796) (xy -1.778 -1.8796) (xy 1.778 -1.8796) (xy 1.778 1.8796)
			)
			(stroke
				(width 0)
				(type default)
			)
			(fill no)
			(layer "F.Fab")
		)
		(pad "D" smd custom
			(at 0 -0.9525 180)
			(size 0.1905 0.1905)
			(layers "F.Cu" "F.Mask" "F.Paste")
			(net "LED_Q_3")
			(options
				(clearance outline)
				(anchor circle)
			)
			(primitives
				(gr_poly
					(pts
						(arc
							(start -0.1778 0.5715)
							(mid -0.321484 0.511984)
							(end -0.381 0.3683)
						)
						(arc
							(start -0.381 -0.3683)
							(mid -0.321484 -0.511984)
							(end -0.1778 -0.5715)
						)
						(arc
							(start 0.1778 -0.5715)
							(mid 0.321484 -0.511984)
							(end 0.381 -0.3683)
						)
						(arc
							(start 0.381 0.3683)
							(mid 0.321484 0.511984)
							(end 0.1778 0.5715)
						)
					)
					(width 0)
					(fill yes)
				)
			)
		)
		(pad "G" smd custom
			(at -0.98425 0.9525 180)
			(size 0.1905 0.1905)
			(layers "F.Cu" "F.Mask" "F.Paste")
			(net "UPLINK3_R")
			(options
				(clearance outline)
				(anchor circle)
			)
			(primitives
				(gr_poly
					(pts
						(arc
							(start -0.1778 0.5715)
							(mid -0.321484 0.511984)
							(end -0.381 0.3683)
						)
						(arc
							(start -0.381 -0.3683)
							(mid -0.321484 -0.511984)
							(end -0.1778 -0.5715)
						)
						(arc
							(start 0.1778 -0.5715)
							(mid 0.321484 -0.511984)
							(end 0.381 -0.3683)
						)
						(arc
							(start 0.381 0.3683)
							(mid 0.321484 0.511984)
							(end 0.1778 0.5715)
						)
					)
					(width 0)
					(fill yes)
				)
			)
		)
		(pad "S" smd custom
			(at 0.98425 0.9525 180)
			(size 0.1905 0.1905)
			(layers "F.Cu" "F.Mask" "F.Paste")
			(net "GND")
			(options
				(clearance outline)
				(anchor circle)
			)
			(primitives
				(gr_poly
					(pts
						(arc
							(start -0.1778 0.5715)
							(mid -0.321484 0.511984)
							(end -0.381 0.3683)
						)
						(arc
							(start -0.381 -0.3683)
							(mid -0.321484 -0.511984)
							(end -0.1778 -0.5715)
						)
						(arc
							(start 0.1778 -0.5715)
							(mid 0.321484 -0.511984)
							(end 0.381 -0.3683)
						)
						(arc
							(start 0.381 0.3683)
							(mid 0.321484 0.511984)
							(end 0.1778 0.5715)
						)
					)
					(width 0)
					(fill yes)
				)
			)
		)
	)
	(footprint ""
		(layer "F.Cu")
		(at 211.455 -0.508 -90)
		(property "Reference" "R5774"
			(at 0 0 270)
			(layer "F.SilkS")
			(hide yes)
			(effects
				(font
					(size 1.27 1.27)
				)
			)
		)
		(property "Value" "330R1210J-GP"
			(at 0.0889 -6.9977 270)
			(unlocked yes)
			(layer "F.Fab")
			(hide yes)
			(effects
				(font
					(size 1.016 1.016)
					(thickness 0.1524)
				)
			)
		)
		(property "Device Type" "R1210H24"
			(at 0.0635 -8.636 270)
			(unlocked yes)
			(layer "F.Fab")
			(hide yes)
			(effects
				(font
					(size 1.016 1.016)
					(thickness 0.1524)
				)
			)
		)
		(duplicate_pad_numbers_are_jumpers no)
		(fp_line
			(start -1.651 2.413)
			(end -1.651 -2.413)
			(stroke
				(width 0.1524)
				(type default)
			)
			(layer "F.SilkS")
		)
		(fp_line
			(start 1.651 2.413)
			(end -1.651 2.413)
			(stroke
				(width 0.1524)
				(type default)
			)
			(layer "F.SilkS")
		)
		(fp_line
			(start -1.651 -2.413)
			(end 1.651 -2.413)
			(stroke
				(width 0.1524)
				(type default)
			)
			(layer "F.SilkS")
		)
		(fp_line
			(start 1.651 -2.413)
			(end 1.651 2.413)
			(stroke
				(width 0.1524)
				(type default)
			)
			(layer "F.SilkS")
		)
		(fp_poly
			(pts
				(xy -1.651 -2.413) (xy 1.651 -2.413) (xy 1.651 2.413) (xy -1.651 2.413)
			)
			(stroke
				(width 0)
				(type default)
			)
			(fill no)
			(layer "F.CrtYd")
		)
		(fp_poly
			(pts
				(xy -1.651 -2.413) (xy 1.651 -2.413) (xy 1.651 2.413) (xy -1.651 2.413)
			)
			(stroke
				(width 0)
				(type default)
			)
			(fill no)
			(layer "F.Fab")
		)
		(pad "1" smd rect
			(at 0 -1.4732 270)
			(size 2.794 1.397)
			(layers "F.Cu" "F.Mask" "F.Paste")
			(net "P5V_STBY")
		)
		(pad "2" smd rect
			(at 0 1.4732 270)
			(size 2.794 1.397)
			(layers "F.Cu" "F.Mask" "F.Paste")
			(net "LED_PWR_N_R")
		)
	)
	(footprint ""
		(layer "F.Cu")
		(at 185.15584 -4.27482)
		(property "Reference" "R2935"
			(at 0 0 0)
			(layer "F.SilkS")
			(hide yes)
			(effects
				(font
					(size 1.27 1.27)
				)
			)
		)
		(property "Value" "0R2J-2-GP"
			(at 0.064008 -3.993896 0)
			(unlocked yes)
			(layer "F.Fab")
			(hide yes)
			(effects
				(font
					(size 1.016 1.016)
					(thickness 0.1524)
				)
			)
		)
		(property "Device Type" "R402H16"
			(at 0.064008 -5.517896 0)
			(unlocked yes)
			(layer "F.Fab")
			(hide yes)
			(effects
				(font
					(size 1.016 1.016)
					(thickness 0.1524)
				)
			)
		)
		(duplicate_pad_numbers_are_jumpers no)
		(fp_line
			(start -0.508 -0.9398)
			(end -0.508 0.9398)
			(stroke
				(width 0.1524)
				(type default)
			)
			(layer "F.SilkS")
		)
		(fp_line
			(start 0.508 -0.9398)
			(end -0.508 -0.9398)
			(stroke
				(width 0.1524)
				(type default)
			)
			(layer "F.SilkS")
		)
		(fp_rect
			(start -0.508 0.9398)
			(end 0.508 -0.9398)
			(stroke
				(width 0)
				(type default)
			)
			(fill no)
			(layer "F.CrtYd")
		)
		(fp_rect
			(start -0.508 0.9398)
			(end 0.508 -0.9398)
			(stroke
				(width 0)
				(type default)
			)
			(fill no)
			(layer "F.Fab")
		)
		(pad "1" smd custom
			(at 0 -0.4445)
			(size 0.1397 0.1397)
			(layers "F.Cu" "F.Mask" "F.Paste")
			(net "HOST1_RST_N")
			(options
				(clearance outline)
				(anchor circle)
			)
			(primitives
				(gr_poly
					(pts
						(arc
							(start -0.1778 -0.2794)
							(mid -0.249642 -0.249642)
							(end -0.2794 -0.1778)
						)
						(arc
							(start -0.2794 0.1778)
							(mid -0.249642 0.249642)
							(end -0.1778 0.2794)
						)
						(arc
							(start 0.1778 0.2794)
							(mid 0.249642 0.249642)
							(end 0.2794 0.1778)
						)
						(arc
							(start 0.2794 -0.1778)
							(mid 0.249642 -0.249642)
							(end 0.1778 -0.2794)
						)
					)
					(width 0)
					(fill yes)
				)
			)
		)
		(pad "2" smd custom
			(at 0 0.4445)
			(size 0.1397 0.1397)
			(layers "F.Cu" "F.Mask" "F.Paste")
			(net "HOST1_RST_N_C")
			(options
				(clearance outline)
				(anchor circle)
			)
			(primitives
				(gr_poly
					(pts
						(arc
							(start -0.1778 -0.2794)
							(mid -0.249642 -0.249642)
							(end -0.2794 -0.1778)
						)
						(arc
							(start -0.2794 0.1778)
							(mid -0.249642 0.249642)
							(end -0.1778 0.2794)
						)
						(arc
							(start 0.1778 0.2794)
							(mid 0.249642 0.249642)
							(end 0.2794 0.1778)
						)
						(arc
							(start 0.2794 -0.1778)
							(mid 0.249642 -0.249642)
							(end 0.1778 -0.2794)
						)
					)
					(width 0)
					(fill yes)
				)
			)
		)
	)
	(footprint ""
		(layer "F.Cu")
		(at 40.7162 -118.3386)
		(property "Reference" "TP293"
			(at 0 0 0)
			(layer "F.SilkS")
			(hide yes)
			(effects
				(font
					(size 1.27 1.27)
				)
			)
		)
		(property "Value" "TPAD28-2-GP"
			(at -0.0127 -1.6637 0)
			(unlocked yes)
			(layer "F.Fab")
			(hide yes)
			(effects
				(font
					(size 1.016 1.016)
					(thickness 0.1524)
				)
			)
		)
		(property "Device Type" "TPAD28"
			(at -0.0127 -3.1877 0)
			(unlocked yes)
			(layer "F.Fab")
			(hide yes)
			(effects
				(font
					(size 1.016 1.016)
					(thickness 0.1524)
				)
			)
		)
		(duplicate_pad_numbers_are_jumpers no)
		(fp_poly
			(pts
				(arc
					(start 0.3556 0)
					(mid -0.3556 0)
					(end 0.3556 0)
				)
			)
			(stroke
				(width 0)
				(type default)
			)
			(fill no)
			(layer "F.CrtYd")
		)
		(fp_poly
			(pts
				(arc
					(start 0.6096 0)
					(mid -0.6096 0)
					(end 0.6096 0)
				)
			)
			(stroke
				(width 0)
				(type default)
			)
			(fill no)
			(layer "F.Fab")
		)
		(pad "1" smd circle
			(at 0 0)
			(size 0.7112 0.7112)
			(layers "F.Cu" "F.Mask" "F.Paste")
			(net "TP_GPIOV4")
		)
	)
	(footprint ""
		(layer "F.Cu")
		(at 150.622 -33.528)
		(property "Reference" "C389"
			(at 0 0 0)
			(layer "F.SilkS")
			(hide yes)
			(effects
				(font
					(size 1.27 1.27)
				)
			)
		)
		(property "Value" "SCD22U10V2KX-1GP"
			(at 1.1811 -2.7051 0)
			(unlocked yes)
			(layer "F.Fab")
			(hide yes)
			(effects
				(font
					(size 1.016 1.016)
					(thickness 0.1524)
				)
			)
		)
		(property "Device Type" "C402H22"
			(at 1.1811 -4.2291 0)
			(unlocked yes)
			(layer "F.Fab")
			(hide yes)
			(effects
				(font
					(size 1.016 1.016)
					(thickness 0.1524)
				)
			)
		)
		(duplicate_pad_numbers_are_jumpers no)
		(fp_rect
			(start -0.4318 0.9525)
			(end 0.4318 -0.9525)
			(stroke
				(width 0)
				(type default)
			)
			(fill no)
			(layer "F.CrtYd")
		)
		(fp_rect
			(start -0.4318 0.9525)
			(end 0.4318 -0.9525)
			(stroke
				(width 0)
				(type default)
			)
			(fill no)
			(layer "F.Fab")
		)
		(pad "1" smd custom
			(at 0 -0.4445)
			(size 0.1524 0.1524)
			(layers "F.Cu" "F.Mask" "F.Paste")
			(net "PCIE_TX_CAP_P84")
			(options
				(clearance outline)
				(anchor circle)
			)
			(primitives
				(gr_poly
					(pts
						(arc
							(start 0.3048 -0.2032)
							(mid 0.275042 -0.275042)
							(end 0.2032 -0.3048)
						)
						(arc
							(start -0.2032 -0.3048)
							(mid -0.275042 -0.275042)
							(end -0.3048 -0.2032)
						)
						(arc
							(start -0.3048 0.2032)
							(mid -0.275042 0.275042)
							(end -0.2032 0.3048)
						)
						(arc
							(start 0.2032 0.3048)
							(mid 0.275042 0.275042)
							(end 0.3048 0.2032)
						)
					)
					(width 0)
					(fill yes)
				)
			)
		)
		(pad "2" smd custom
			(at 0 0.4445)
			(size 0.1524 0.1524)
			(layers "F.Cu" "F.Mask" "F.Paste")
			(net "PCIE_TX_P84")
			(options
				(clearance outline)
				(anchor circle)
			)
			(primitives
				(gr_poly
					(pts
						(arc
							(start 0.3048 -0.2032)
							(mid 0.275042 -0.275042)
							(end 0.2032 -0.3048)
						)
						(arc
							(start -0.2032 -0.3048)
							(mid -0.275042 -0.275042)
							(end -0.3048 -0.2032)
						)
						(arc
							(start -0.3048 0.2032)
							(mid -0.275042 0.275042)
							(end -0.2032 0.3048)
						)
						(arc
							(start 0.2032 0.3048)
							(mid 0.275042 0.275042)
							(end 0.3048 0.2032)
						)
					)
					(width 0)
					(fill yes)
				)
			)
		)
	)
	(footprint ""
		(layer "F.Cu")
		(at 65.7606 -75.0062)
		(property "Reference" "R733"
			(at 0 0 0)
			(layer "F.SilkS")
			(hide yes)
			(effects
				(font
					(size 1.27 1.27)
				)
			)
		)
		(property "Value" "0R2J-2-GP"
			(at 0.064008 -3.993896 0)
			(unlocked yes)
			(layer "F.Fab")
			(hide yes)
			(effects
				(font
					(size 1.016 1.016)
					(thickness 0.1524)
				)
			)
		)
		(property "Device Type" "R402H16"
			(at 0.064008 -5.517896 0)
			(unlocked yes)
			(layer "F.Fab")
			(hide yes)
			(effects
				(font
					(size 1.016 1.016)
					(thickness 0.1524)
				)
			)
		)
		(duplicate_pad_numbers_are_jumpers no)
		(fp_line
			(start -0.508 -0.9398)
			(end -0.508 0.9398)
			(stroke
				(width 0.1524)
				(type default)
			)
			(layer "F.SilkS")
		)
		(fp_line
			(start 0.508 -0.9398)
			(end -0.508 -0.9398)
			(stroke
				(width 0.1524)
				(type default)
			)
			(layer "F.SilkS")
		)
		(fp_rect
			(start -0.508 0.9398)
			(end 0.508 -0.9398)
			(stroke
				(width 0)
				(type default)
			)
			(fill no)
			(layer "F.CrtYd")
		)
		(fp_rect
			(start -0.508 0.9398)
			(end 0.508 -0.9398)
			(stroke
				(width 0)
				(type default)
			)
			(fill no)
			(layer "F.Fab")
		)
		(pad "1" smd custom
			(at 0 -0.4445)
			(size 0.1397 0.1397)
			(layers "F.Cu" "F.Mask" "F.Paste")
			(net "FM_BMC_RESET_N")
			(options
				(clearance outline)
				(anchor circle)
			)
			(primitives
				(gr_poly
					(pts
						(arc
							(start -0.1778 -0.2794)
							(mid -0.249642 -0.249642)
							(end -0.2794 -0.1778)
						)
						(arc
							(start -0.2794 0.1778)
							(mid -0.249642 0.249642)
							(end -0.1778 0.2794)
						)
						(arc
							(start 0.1778 0.2794)
							(mid 0.249642 0.249642)
							(end 0.2794 0.1778)
						)
						(arc
							(start 0.2794 -0.1778)
							(mid 0.249642 -0.249642)
							(end 0.1778 -0.2794)
						)
					)
					(width 0)
					(fill yes)
				)
			)
		)
		(pad "2" smd custom
			(at 0 0.4445)
			(size 0.1397 0.1397)
			(layers "F.Cu" "F.Mask" "F.Paste")
			(net "U19_PERST_N")
			(options
				(clearance outline)
				(anchor circle)
			)
			(primitives
				(gr_poly
					(pts
						(arc
							(start -0.1778 -0.2794)
							(mid -0.249642 -0.249642)
							(end -0.2794 -0.1778)
						)
						(arc
							(start -0.2794 0.1778)
							(mid -0.249642 0.249642)
							(end -0.1778 0.2794)
						)
						(arc
							(start 0.1778 0.2794)
							(mid 0.249642 0.249642)
							(end 0.2794 0.1778)
						)
						(arc
							(start 0.2794 -0.1778)
							(mid 0.249642 -0.249642)
							(end 0.1778 -0.2794)
						)
					)
					(width 0)
					(fill yes)
				)
			)
		)
	)
)
